(kicad_pcb
	(version 20260206)
	(generator "pcbnew")
	(generator_version "10.0")
	(general
		(thickness 1.6)
		(legacy_teardrops no)
	)
	(paper "A4")
	(title_block
		(title "01162023_DA0F0TEBIF0_F0T_Expander_BD_F_brd_V02_OCP.brd")
		(comment 1 "Grand Teton / footprints 3787-3792 of 9728")
	)
	(layers
		(0 "F.Cu" signal "TOP")
		(4 "In1.Cu" signal "GND")
		(6 "In2.Cu" signal "VCC")
		(8 "In3.Cu" signal "VCC1")
		(10 "In4.Cu" signal "GND1")
		(12 "In5.Cu" signal "IN1")
		(14 "In6.Cu" signal "GND2")
		(16 "In7.Cu" signal "IN2")
		(18 "In8.Cu" signal "GND3")
		(20 "In9.Cu" signal "IN3")
		(22 "In10.Cu" signal "GND4")
		(24 "In11.Cu" signal "IN4")
		(26 "In12.Cu" signal "GND5")
		(28 "In13.Cu" signal "IN5")
		(30 "In14.Cu" signal "GND6")
		(32 "In15.Cu" signal "IN6")
		(34 "In16.Cu" signal "GND7")
		(2 "B.Cu" signal "BOTTOM")
		(9 "F.Adhes" user "F.Adhesive")
		(11 "B.Adhes" user "B.Adhesive")
		(13 "F.Paste" user "Package Geometry/Pastemask Top")
		(15 "B.Paste" user "Package Geometry/Pastemask Bottom")
		(5 "F.SilkS" user "Ref Des/Silkscreen Top")
		(7 "B.SilkS" user "Ref Des/Silkscreen Bottom")
		(1 "F.Mask" user "Board Geometry/Soldermask Top")
		(3 "B.Mask" user "Board Geometry/Soldermask Bottom")
		(17 "Dwgs.User" user "User.Drawings")
		(19 "Cmts.User" user "User.Comments")
		(21 "Eco1.User" user "User.Eco1")
		(23 "Eco2.User" user "User.Eco2")
		(25 "Edge.Cuts" user "Board Geometry/Outline")
		(27 "Margin" user)
		(31 "F.CrtYd" user "Package Geometry/Place Bound Top")
		(29 "B.CrtYd" user "Package Geometry/Place Bound Bottom")
		(35 "F.Fab" user "Ref Des/Assembly Top")
		(33 "B.Fab" user "Ref Des/Assembly Bottom")
	)
	(footprint ""
		(layer "F.Cu")
		(at 164.06114 -37.951156)
		(property "Reference" "Q222"
			(at -0.02794 -1.925574 0)
			(unlocked yes)
			(layer "F.SilkS")
			(effects
				(font
					(size 0.7874 0.5842)
					(thickness 0.1524)
				)
			)
		)
		(property "Value" ""
			(at 0 0 0)
			(layer "F.Fab")
			(effects
				(font
					(size 1.27 1.27)
				)
			)
		)
		(duplicate_pad_numbers_are_jumpers no)
		(fp_line
			(start -1.376172 -1.199896)
			(end -0.508 -1.199896)
			(stroke
				(width 0.1524)
				(type default)
			)
			(layer "F.SilkS")
		)
		(fp_line
			(start -1.376172 1.199896)
			(end -1.376172 -1.199896)
			(stroke
				(width 0.1524)
				(type default)
			)
			(layer "F.SilkS")
		)
		(fp_line
			(start -0.508 -1.199896)
			(end 0 -0.762)
			(stroke
				(width 0.1524)
				(type default)
			)
			(layer "F.SilkS")
		)
		(fp_line
			(start 0 -0.762)
			(end 0.508 -1.199896)
			(stroke
				(width 0.1524)
				(type default)
			)
			(layer "F.SilkS")
		)
		(fp_line
			(start 0.508 -1.199896)
			(end 1.376172 -1.199896)
			(stroke
				(width 0.1524)
				(type default)
			)
			(layer "F.SilkS")
		)
		(fp_line
			(start 1.376172 -1.199896)
			(end 1.376172 1.199896)
			(stroke
				(width 0.1524)
				(type default)
			)
			(layer "F.SilkS")
		)
		(fp_line
			(start 1.376172 1.199896)
			(end -1.376172 1.199896)
			(stroke
				(width 0.1524)
				(type default)
			)
			(layer "F.SilkS")
		)
		(fp_poly
			(pts
				(xy -1.471422 -0.894334) (xy -1.740916 -1.702562) (xy -2.27965 -1.163828)
			)
			(stroke
				(width 0)
				(type default)
			)
			(fill yes)
			(layer "F.SilkS")
		)
		(fp_line
			(start -0.674878 -1.100074)
			(end 0.674878 -1.100074)
			(stroke
				(width 0.1)
				(type default)
			)
			(layer "F.Fab")
		)
		(fp_line
			(start -0.674878 1.100074)
			(end -0.674878 -1.100074)
			(stroke
				(width 0.1)
				(type default)
			)
			(layer "F.Fab")
		)
		(fp_line
			(start 0.674878 -1.100074)
			(end 0.674878 1.100074)
			(stroke
				(width 0.1)
				(type default)
			)
			(layer "F.Fab")
		)
		(fp_line
			(start 0.674878 1.100074)
			(end -0.674878 1.100074)
			(stroke
				(width 0.1)
				(type default)
			)
			(layer "F.Fab")
		)
		(fp_poly
			(pts
				(xy -1.4605 -0.7493) (xy -2.2225 -1.1303) (xy -2.2225 -0.3683)
			)
			(stroke
				(width 0)
				(type default)
			)
			(fill yes)
			(layer "F.Fab")
		)
		(pad "1" smd rect
			(at -0.899922 -0.750062 270)
			(size 0.6096 0.6096)
			(layers "F.Cu" "F.Mask" "F.Paste")
			(net "GND")
		)
		(pad "2" smd rect
			(at -0.899922 0 270)
			(size 0.4064 0.6096)
			(layers "F.Cu" "F.Mask" "F.Paste")
			(net "P3V3_SSD6_PG_G1")
		)
		(pad "3" smd rect
			(at -0.899922 0.750062 270)
			(size 0.6096 0.6096)
			(layers "F.Cu" "F.Mask" "F.Paste")
			(net "PWRGD_P3V3_SSD6_D")
		)
		(pad "4" smd rect
			(at 0.899922 0.750062 270)
			(size 0.6096 0.6096)
			(layers "F.Cu" "F.Mask" "F.Paste")
			(net "GND")
		)
		(pad "5" smd rect
			(at 0.899922 0 270)
			(size 0.4064 0.6096)
			(layers "F.Cu" "F.Mask" "F.Paste")
			(net "P3V3_SSD6_PG_G2")
		)
		(pad "6" smd rect
			(at 0.899922 -0.750062 270)
			(size 0.6096 0.6096)
			(layers "F.Cu" "F.Mask" "F.Paste")
			(net "P3V3_SSD6_PG_G2")
		)
	)
	(footprint ""
		(layer "F.Cu")
		(at 112.937798 -157.595824)
		(property "Reference" "PC31"
			(at 0 0 0)
			(layer "F.SilkS")
			(hide yes)
			(effects
				(font
					(size 1.27 1.27)
				)
			)
		)
		(property "Value" ""
			(at 0 0 0)
			(layer "F.Fab")
			(effects
				(font
					(size 1.27 1.27)
				)
			)
		)
		(duplicate_pad_numbers_are_jumpers no)
		(fp_line
			(start -0.7874 -0.4064)
			(end 0.7874 -0.4064)
			(stroke
				(width 0.1524)
				(type default)
			)
			(layer "F.SilkS")
		)
		(fp_line
			(start -0.7874 0.4064)
			(end -0.7874 -0.4064)
			(stroke
				(width 0.1524)
				(type default)
			)
			(layer "F.SilkS")
		)
		(fp_line
			(start 0.7874 -0.4064)
			(end 0.7874 0.4064)
			(stroke
				(width 0.1524)
				(type default)
			)
			(layer "F.SilkS")
		)
		(fp_line
			(start 0.7874 0.4064)
			(end -0.7874 0.4064)
			(stroke
				(width 0.1524)
				(type default)
			)
			(layer "F.SilkS")
		)
		(fp_line
			(start -0.67945 -0.305054)
			(end -0.12065 -0.305054)
			(stroke
				(width 0.1)
				(type default)
			)
			(layer "F.Fab")
		)
		(fp_line
			(start -0.67945 0.3048)
			(end -0.67945 -0.305054)
			(stroke
				(width 0.1)
				(type default)
			)
			(layer "F.Fab")
		)
		(fp_line
			(start -0.12065 -0.305054)
			(end -0.12065 -0.2794)
			(stroke
				(width 0.1)
				(type default)
			)
			(layer "F.Fab")
		)
		(fp_line
			(start -0.12065 -0.2794)
			(end 0.12065 -0.2794)
			(stroke
				(width 0.1)
				(type default)
			)
			(layer "F.Fab")
		)
		(fp_line
			(start -0.12065 0.2794)
			(end -0.12065 0.3048)
			(stroke
				(width 0.1)
				(type default)
			)
			(layer "F.Fab")
		)
		(fp_line
			(start -0.12065 0.3048)
			(end -0.67945 0.3048)
			(stroke
				(width 0.1)
				(type default)
			)
			(layer "F.Fab")
		)
		(fp_line
			(start 0.120396 0.2794)
			(end -0.12065 0.2794)
			(stroke
				(width 0.1)
				(type default)
			)
			(layer "F.Fab")
		)
		(fp_line
			(start 0.120396 0.3048)
			(end 0.120396 0.2794)
			(stroke
				(width 0.1)
				(type default)
			)
			(layer "F.Fab")
		)
		(fp_line
			(start 0.12065 -0.3048)
			(end 0.67945 -0.3048)
			(stroke
				(width 0.1)
				(type default)
			)
			(layer "F.Fab")
		)
		(fp_line
			(start 0.12065 -0.2794)
			(end 0.12065 -0.3048)
			(stroke
				(width 0.1)
				(type default)
			)
			(layer "F.Fab")
		)
		(fp_line
			(start 0.67945 -0.3048)
			(end 0.67945 0.3048)
			(stroke
				(width 0.1)
				(type default)
			)
			(layer "F.Fab")
		)
		(fp_line
			(start 0.67945 0.3048)
			(end 0.120396 0.3048)
			(stroke
				(width 0.1)
				(type default)
			)
			(layer "F.Fab")
		)
		(pad "1" smd circle
			(at -0.40005 0)
			(size 0 0)
			(layers "F.Cu" "F.Mask" "F.Paste")
			(net "SW_P3V3_AUX_BT")
		)
		(pad "2" smd circle
			(at 0.40005 0)
			(size 0 0)
			(layers "F.Cu" "F.Mask" "F.Paste")
			(net "SW_P3V3_AUX_PH")
		)
	)
	(footprint ""
		(layer "F.Cu")
		(at 238.48822 -55.808118 90)
		(property "Reference" "PC553"
			(at 0 0 90)
			(layer "F.SilkS")
			(hide yes)
			(effects
				(font
					(size 1.27 1.27)
				)
			)
		)
		(property "Value" ""
			(at 0 0 90)
			(layer "F.Fab")
			(effects
				(font
					(size 1.27 1.27)
				)
			)
		)
		(duplicate_pad_numbers_are_jumpers no)
		(fp_line
			(start 0.7874 -0.4064)
			(end 0.7874 0.4064)
			(stroke
				(width 0.1524)
				(type default)
			)
			(layer "F.SilkS")
		)
		(fp_line
			(start -0.7874 -0.4064)
			(end 0.7874 -0.4064)
			(stroke
				(width 0.1524)
				(type default)
			)
			(layer "F.SilkS")
		)
		(fp_line
			(start 0.7874 0.4064)
			(end -0.7874 0.4064)
			(stroke
				(width 0.1524)
				(type default)
			)
			(layer "F.SilkS")
		)
		(fp_line
			(start -0.7874 0.4064)
			(end -0.7874 -0.4064)
			(stroke
				(width 0.1524)
				(type default)
			)
			(layer "F.SilkS")
		)
		(fp_line
			(start -0.12065 -0.305054)
			(end -0.12065 -0.2794)
			(stroke
				(width 0.1)
				(type default)
			)
			(layer "F.Fab")
		)
		(fp_line
			(start -0.67945 -0.305054)
			(end -0.12065 -0.305054)
			(stroke
				(width 0.1)
				(type default)
			)
			(layer "F.Fab")
		)
		(fp_line
			(start 0.67945 -0.3048)
			(end 0.67945 0.3048)
			(stroke
				(width 0.1)
				(type default)
			)
			(layer "F.Fab")
		)
		(fp_line
			(start 0.12065 -0.3048)
			(end 0.67945 -0.3048)
			(stroke
				(width 0.1)
				(type default)
			)
			(layer "F.Fab")
		)
		(fp_line
			(start 0.12065 -0.2794)
			(end 0.12065 -0.3048)
			(stroke
				(width 0.1)
				(type default)
			)
			(layer "F.Fab")
		)
		(fp_line
			(start -0.12065 -0.2794)
			(end 0.12065 -0.2794)
			(stroke
				(width 0.1)
				(type default)
			)
			(layer "F.Fab")
		)
		(fp_line
			(start 0.120396 0.2794)
			(end -0.12065 0.2794)
			(stroke
				(width 0.1)
				(type default)
			)
			(layer "F.Fab")
		)
		(fp_line
			(start -0.12065 0.2794)
			(end -0.12065 0.3048)
			(stroke
				(width 0.1)
				(type default)
			)
			(layer "F.Fab")
		)
		(fp_line
			(start 0.67945 0.3048)
			(end 0.120396 0.3048)
			(stroke
				(width 0.1)
				(type default)
			)
			(layer "F.Fab")
		)
		(fp_line
			(start 0.120396 0.3048)
			(end 0.120396 0.2794)
			(stroke
				(width 0.1)
				(type default)
			)
			(layer "F.Fab")
		)
		(fp_line
			(start -0.12065 0.3048)
			(end -0.67945 0.3048)
			(stroke
				(width 0.1)
				(type default)
			)
			(layer "F.Fab")
		)
		(fp_line
			(start -0.67945 0.3048)
			(end -0.67945 -0.305054)
			(stroke
				(width 0.1)
				(type default)
			)
			(layer "F.Fab")
		)
		(pad "1" smd circle
			(at -0.40005 0 90)
			(size 0 0)
			(layers "F.Cu" "F.Mask" "F.Paste")
			(net "P5V_AUX")
		)
		(pad "2" smd circle
			(at 0.40005 0 90)
			(size 0 0)
			(layers "F.Cu" "F.Mask" "F.Paste")
			(net "GND")
		)
	)
	(footprint ""
		(layer "F.Cu")
		(at 121.13514 -94.891606)
		(property "Reference" "R1553"
			(at 0 0 0)
			(layer "F.SilkS")
			(hide yes)
			(effects
				(font
					(size 1.27 1.27)
				)
			)
		)
		(property "Value" ""
			(at 0 0 0)
			(layer "F.Fab")
			(effects
				(font
					(size 1.27 1.27)
				)
			)
		)
		(duplicate_pad_numbers_are_jumpers no)
		(fp_line
			(start -0.7874 -0.4064)
			(end 0.7874 -0.4064)
			(stroke
				(width 0.1524)
				(type default)
			)
			(layer "F.SilkS")
		)
		(fp_line
			(start -0.7874 0.4064)
			(end -0.7874 -0.4064)
			(stroke
				(width 0.1524)
				(type default)
			)
			(layer "F.SilkS")
		)
		(fp_line
			(start 0.7874 -0.4064)
			(end 0.7874 0.4064)
			(stroke
				(width 0.1524)
				(type default)
			)
			(layer "F.SilkS")
		)
		(fp_line
			(start 0.7874 0.4064)
			(end -0.7874 0.4064)
			(stroke
				(width 0.1524)
				(type default)
			)
			(layer "F.SilkS")
		)
		(fp_line
			(start -0.67945 -0.305054)
			(end -0.12065 -0.305054)
			(stroke
				(width 0.1)
				(type default)
			)
			(layer "F.Fab")
		)
		(fp_line
			(start -0.67945 0.3048)
			(end -0.67945 -0.305054)
			(stroke
				(width 0.1)
				(type default)
			)
			(layer "F.Fab")
		)
		(fp_line
			(start -0.12065 -0.305054)
			(end -0.12065 -0.2794)
			(stroke
				(width 0.1)
				(type default)
			)
			(layer "F.Fab")
		)
		(fp_line
			(start -0.12065 -0.2794)
			(end 0.12065 -0.2794)
			(stroke
				(width 0.1)
				(type default)
			)
			(layer "F.Fab")
		)
		(fp_line
			(start -0.12065 0.2794)
			(end -0.12065 0.3048)
			(stroke
				(width 0.1)
				(type default)
			)
			(layer "F.Fab")
		)
		(fp_line
			(start -0.12065 0.3048)
			(end -0.67945 0.3048)
			(stroke
				(width 0.1)
				(type default)
			)
			(layer "F.Fab")
		)
		(fp_line
			(start 0.120396 0.2794)
			(end -0.12065 0.2794)
			(stroke
				(width 0.1)
				(type default)
			)
			(layer "F.Fab")
		)
		(fp_line
			(start 0.120396 0.3048)
			(end 0.120396 0.2794)
			(stroke
				(width 0.1)
				(type default)
			)
			(layer "F.Fab")
		)
		(fp_line
			(start 0.12065 -0.3048)
			(end 0.67945 -0.3048)
			(stroke
				(width 0.1)
				(type default)
			)
			(layer "F.Fab")
		)
		(fp_line
			(start 0.12065 -0.2794)
			(end 0.12065 -0.3048)
			(stroke
				(width 0.1)
				(type default)
			)
			(layer "F.Fab")
		)
		(fp_line
			(start 0.67945 -0.3048)
			(end 0.67945 0.3048)
			(stroke
				(width 0.1)
				(type default)
			)
			(layer "F.Fab")
		)
		(fp_line
			(start 0.67945 0.3048)
			(end 0.120396 0.3048)
			(stroke
				(width 0.1)
				(type default)
			)
			(layer "F.Fab")
		)
		(pad "1" smd circle
			(at -0.40005 0)
			(size 0 0)
			(layers "F.Cu" "F.Mask" "F.Paste")
			(net "P3V3_AUX")
		)
		(pad "2" smd circle
			(at 0.40005 0)
			(size 0 0)
			(layers "F.Cu" "F.Mask" "F.Paste")
			(net "SMB_BIC_I2C9_MUX0_SSD1_R_SDA")
		)
	)
	(footprint ""
		(layer "F.Cu")
		(at 212.65769 -233.830622 -90)
		(property "Reference" "R1541"
			(at 0 0 270)
			(layer "F.SilkS")
			(hide yes)
			(effects
				(font
					(size 1.27 1.27)
				)
			)
		)
		(property "Value" ""
			(at 0 0 270)
			(layer "F.Fab")
			(effects
				(font
					(size 1.27 1.27)
				)
			)
		)
		(duplicate_pad_numbers_are_jumpers no)
		(fp_line
			(start -0.7874 0.4064)
			(end -0.7874 -0.4064)
			(stroke
				(width 0.1524)
				(type default)
			)
			(layer "F.SilkS")
		)
		(fp_line
			(start 0.7874 0.4064)
			(end -0.7874 0.4064)
			(stroke
				(width 0.1524)
				(type default)
			)
			(layer "F.SilkS")
		)
		(fp_line
			(start -0.7874 -0.4064)
			(end 0.7874 -0.4064)
			(stroke
				(width 0.1524)
				(type default)
			)
			(layer "F.SilkS")
		)
		(fp_line
			(start 0.7874 -0.4064)
			(end 0.7874 0.4064)
			(stroke
				(width 0.1524)
				(type default)
			)
			(layer "F.SilkS")
		)
		(fp_line
			(start -0.67945 0.3048)
			(end -0.67945 -0.305054)
			(stroke
				(width 0.1)
				(type default)
			)
			(layer "F.Fab")
		)
		(fp_line
			(start -0.12065 0.3048)
			(end -0.67945 0.3048)
			(stroke
				(width 0.1)
				(type default)
			)
			(layer "F.Fab")
		)
		(fp_line
			(start 0.120396 0.3048)
			(end 0.120396 0.2794)
			(stroke
				(width 0.1)
				(type default)
			)
			(layer "F.Fab")
		)
		(fp_line
			(start 0.67945 0.3048)
			(end 0.120396 0.3048)
			(stroke
				(width 0.1)
				(type default)
			)
			(layer "F.Fab")
		)
		(fp_line
			(start -0.12065 0.2794)
			(end -0.12065 0.3048)
			(stroke
				(width 0.1)
				(type default)
			)
			(layer "F.Fab")
		)
		(fp_line
			(start 0.120396 0.2794)
			(end -0.12065 0.2794)
			(stroke
				(width 0.1)
				(type default)
			)
			(layer "F.Fab")
		)
		(fp_line
			(start -0.12065 -0.2794)
			(end 0.12065 -0.2794)
			(stroke
				(width 0.1)
				(type default)
			)
			(layer "F.Fab")
		)
		(fp_line
			(start 0.12065 -0.2794)
			(end 0.12065 -0.3048)
			(stroke
				(width 0.1)
				(type default)
			)
			(layer "F.Fab")
		)
		(fp_line
			(start 0.12065 -0.3048)
			(end 0.67945 -0.3048)
			(stroke
				(width 0.1)
				(type default)
			)
			(layer "F.Fab")
		)
		(fp_line
			(start 0.67945 -0.3048)
			(end 0.67945 0.3048)
			(stroke
				(width 0.1)
				(type default)
			)
			(layer "F.Fab")
		)
		(fp_line
			(start -0.67945 -0.305054)
			(end -0.12065 -0.305054)
			(stroke
				(width 0.1)
				(type default)
			)
			(layer "F.Fab")
		)
		(fp_line
			(start -0.12065 -0.305054)
			(end -0.12065 -0.2794)
			(stroke
				(width 0.1)
				(type default)
			)
			(layer "F.Fab")
		)
		(pad "1" smd circle
			(at -0.40005 0 270)
			(size 0 0)
			(layers "F.Cu" "F.Mask" "F.Paste")
			(net "SMB_PEX_LS_R_SCL")
		)
		(pad "2" smd circle
			(at 0.40005 0 270)
			(size 0 0)
			(layers "F.Cu" "F.Mask" "F.Paste")
			(net "SMB_PEX0_SCL")
		)
	)
	(footprint ""
		(layer "F.Cu")
		(at 414.273492 -186.787282)
		(property "Reference" "Q232"
			(at -4.003294 -1.501394 0)
			(unlocked yes)
			(layer "F.SilkS")
			(effects
				(font
					(size 0.7874 0.5842)
					(thickness 0.1524)
				)
			)
		)
		(property "Value" ""
			(at 0 0 0)
			(layer "F.Fab")
			(effects
				(font
					(size 1.27 1.27)
				)
			)
		)
		(duplicate_pad_numbers_are_jumpers no)
		(fp_line
			(start -1.376172 -1.199896)
			(end -0.508 -1.199896)
			(stroke
				(width 0.1524)
				(type default)
			)
			(layer "F.SilkS")
		)
		(fp_line
			(start -1.376172 1.199896)
			(end -1.376172 -1.199896)
			(stroke
				(width 0.1524)
				(type default)
			)
			(layer "F.SilkS")
		)
		(fp_line
			(start -0.508 -1.199896)
			(end 0 -0.762)
			(stroke
				(width 0.1524)
				(type default)
			)
			(layer "F.SilkS")
		)
		(fp_line
			(start 0 -0.762)
			(end 0.508 -1.199896)
			(stroke
				(width 0.1524)
				(type default)
			)
			(layer "F.SilkS")
		)
		(fp_line
			(start 0.508 -1.199896)
			(end 1.376172 -1.199896)
			(stroke
				(width 0.1524)
				(type default)
			)
			(layer "F.SilkS")
		)
		(fp_line
			(start 1.376172 -1.199896)
			(end 1.376172 1.199896)
			(stroke
				(width 0.1524)
				(type default)
			)
			(layer "F.SilkS")
		)
		(fp_line
			(start 1.376172 1.199896)
			(end -1.376172 1.199896)
			(stroke
				(width 0.1524)
				(type default)
			)
			(layer "F.SilkS")
		)
		(fp_poly
			(pts
				(xy -1.4605 -0.7493) (xy -2.2225 -1.1303) (xy -2.2225 -0.3683)
			)
			(stroke
				(width 0)
				(type default)
			)
			(fill yes)
			(layer "F.SilkS")
		)
		(fp_line
			(start -0.674878 -1.100074)
			(end 0.674878 -1.100074)
			(stroke
				(width 0.1)
				(type default)
			)
			(layer "F.Fab")
		)
		(fp_line
			(start -0.674878 1.100074)
			(end -0.674878 -1.100074)
			(stroke
				(width 0.1)
				(type default)
			)
			(layer "F.Fab")
		)
		(fp_line
			(start 0.674878 -1.100074)
			(end 0.674878 1.100074)
			(stroke
				(width 0.1)
				(type default)
			)
			(layer "F.Fab")
		)
		(fp_line
			(start 0.674878 1.100074)
			(end -0.674878 1.100074)
			(stroke
				(width 0.1)
				(type default)
			)
			(layer "F.Fab")
		)
		(fp_poly
			(pts
				(xy -1.4605 -0.7493) (xy -2.2225 -1.1303) (xy -2.2225 -0.3683)
			)
			(stroke
				(width 0)
				(type default)
			)
			(fill yes)
			(layer "F.Fab")
		)
		(pad "1" smd rect
			(at -0.899922 -0.750062 270)
			(size 0.6096 0.6096)
			(layers "F.Cu" "F.Mask" "F.Paste")
			(net "GND")
		)
		(pad "2" smd rect
			(at -0.899922 0 270)
			(size 0.4064 0.6096)
			(layers "F.Cu" "F.Mask" "F.Paste")
			(net "FPGA_PEX0_MODE_SEL2_R")
		)
		(pad "3" smd rect
			(at -0.899922 0.750062 270)
			(size 0.6096 0.6096)
			(layers "F.Cu" "F.Mask" "F.Paste")
			(net "FPGA_PEX0_MODE_SEL2_ISO")
		)
		(pad "4" smd rect
			(at 0.899922 0.750062 270)
			(size 0.6096 0.6096)
			(layers "F.Cu" "F.Mask" "F.Paste")
			(net "GND")
		)
		(pad "5" smd rect
			(at 0.899922 0 270)
			(size 0.4064 0.6096)
			(layers "F.Cu" "F.Mask" "F.Paste")
			(net "FPGA_PEX0_MODE_SEL2_D_N")
		)
		(pad "6" smd rect
			(at 0.899922 -0.750062 270)
			(size 0.6096 0.6096)
			(layers "F.Cu" "F.Mask" "F.Paste")
			(net "FPGA_PEX0_MODE_SEL2_D_N")
		)
	)
)
